# T6G (Grand Teton) — schematic netlist excerpt (pin names and nets, part order shuffled) for the footprints in the layout excerpt that follows; sources: Cadence DE-HDL packaged netlist, KiCad conversion of 04192023_DAF0TMB3IC0_F0TG_MB_C_brd_V02_OCP.brd

C6667  Q_CAP_DIFFBUS  DIFF BUS_0.22UF 6.3V 20% X6S  pkg C0201  page 330 : \1\ = P5E_CPU1_P1_TX_BUF_C_DP<3> ; \2\ = P5E_CPU1_P1_TX_BUF_DP<3>
C146  Q_CAP  10UF 25V 10% X6S  pkg C0805  page 88 : A = P12V_MEM_CPU0 ; B = GND
PC280_2  Q_CAP  22UF 4V 20% X6S  pkg C0805  page 211 : A = PVDDCR_CPU0_P1 ; B = GND
R322  Q_RES  1K 1% EMPTY  pkg 0402LF  page 160 : A = PVDD11_S3_P0 ; B = SMB_CPU0_CPU1_APML_BUF2_SCL_R2

(kicad_pcb
	(version 20260206)
	(generator "pcbnew")
	(generator_version "10.0")
	(general
		(thickness 1.6)
		(legacy_teardrops no)
	)
	(paper "A4")
	(title_block
		(title "04192023_DAF0TMB3IC0_F0TG_MB_C_brd_V02_OCP.brd")
		(comment 1 "Grand Teton / footprints 6705-6708 of 8354")
	)
	(layers
		(0 "F.Cu" signal "TOP")
		(4 "In1.Cu" signal "GND")
		(6 "In2.Cu" signal "IN1")
		(8 "In3.Cu" signal "GND1")
		(10 "In4.Cu" signal "IN2")
		(12 "In5.Cu" signal "GND2")
		(14 "In6.Cu" signal "IN3")
		(16 "In7.Cu" signal "GND3")
		(18 "In8.Cu" signal "VCC")
		(20 "In9.Cu" signal "VCC1")
		(22 "In10.Cu" signal "GND4")
		(24 "In11.Cu" signal "IN4")
		(26 "In12.Cu" signal "GND5")
		(28 "In13.Cu" signal "IN5")
		(30 "In14.Cu" signal "GND6")
		(32 "In15.Cu" signal "IN6")
		(34 "In16.Cu" signal "GND7")
		(2 "B.Cu" signal "BOTTOM")
		(9 "F.Adhes" user "F.Adhesive")
		(11 "B.Adhes" user "B.Adhesive")
		(13 "F.Paste" user "Package Geometry/Pastemask Top")
		(15 "B.Paste" user "Package Geometry/Pastemask Bottom")
		(5 "F.SilkS" user "Ref Des/Silkscreen Top")
		(7 "B.SilkS" user "Ref Des/Silkscreen Bottom")
		(1 "F.Mask" user "Board Geometry/Soldermask Top")
		(3 "B.Mask" user "Board Geometry/Soldermask Bottom")
		(17 "Dwgs.User" user "User.Drawings")
		(19 "Cmts.User" user "User.Comments")
		(21 "Eco1.User" user "User.Eco1")
		(23 "Eco2.User" user "User.Eco2")
		(25 "Edge.Cuts" user "Board Geometry/Outline")
		(27 "Margin" user)
		(31 "F.CrtYd" user "Package Geometry/Place Bound Top")
		(29 "B.CrtYd" user "Package Geometry/Place Bound Bottom")
		(35 "F.Fab" user "Ref Des/Assembly Top")
		(33 "B.Fab" user "Ref Des/Assembly Bottom")
	)
	(footprint ""
		(layer "B.Cu")
		(at 288.180272 -192.660016 180)
		(property "Reference" "C146"
			(at 0 0 0)
			(layer "B.SilkS")
			(hide yes)
			(effects
				(font
					(size 1.27 1.27)
				)
				(justify mirror)
			)
		)
		(property "Value" ""
			(at 0 0 0)
			(layer "B.Fab")
			(effects
				(font
					(size 1.27 1.27)
				)
				(justify mirror)
			)
		)
		(duplicate_pad_numbers_are_jumpers no)
		(fp_line
			(start 1.524 0.762)
			(end 1.524 -0.762)
			(stroke
				(width 0.1524)
				(type default)
			)
			(layer "B.SilkS")
		)
		(fp_line
			(start 1.524 -0.762)
			(end -1.524 -0.762)
			(stroke
				(width 0.1524)
				(type default)
			)
			(layer "B.SilkS")
		)
		(fp_line
			(start -1.524 0.762)
			(end 1.524 0.762)
			(stroke
				(width 0.1524)
				(type default)
			)
			(layer "B.SilkS")
		)
		(fp_line
			(start -1.524 -0.762)
			(end -1.524 0.762)
			(stroke
				(width 0.1524)
				(type default)
			)
			(layer "B.SilkS")
		)
		(fp_line
			(start 1.1049 0.724916)
			(end -1.1049 0.724916)
			(stroke
				(width 0.1)
				(type default)
			)
			(layer "B.Fab")
		)
		(fp_line
			(start 1.1049 -0.724916)
			(end 1.1049 0.724916)
			(stroke
				(width 0.1)
				(type default)
			)
			(layer "B.Fab")
		)
		(fp_line
			(start -1.1049 0.724916)
			(end -1.1049 -0.724916)
			(stroke
				(width 0.1)
				(type default)
			)
			(layer "B.Fab")
		)
		(fp_line
			(start -1.1049 -0.724916)
			(end 1.1049 -0.724916)
			(stroke
				(width 0.1)
				(type default)
			)
			(layer "B.Fab")
		)
		(pad "1" smd rect
			(at 0.889 0 180)
			(size 1.016 1.27)
			(layers "B.Cu" "B.Mask" "B.Paste")
			(net "P12V_MEM_CPU0")
		)
		(pad "2" smd rect
			(at -0.889 0 180)
			(size 1.016 1.27)
			(layers "B.Cu" "B.Mask" "B.Paste")
			(net "GND")
		)
	)
	(footprint ""
		(layer "B.Cu")
		(at 76.753974 -186.316112 90)
		(property "Reference" "PC280_2"
			(at 0 0 90)
			(layer "B.SilkS")
			(hide yes)
			(effects
				(font
					(size 1.27 1.27)
				)
				(justify mirror)
			)
		)
		(property "Value" ""
			(at 0 0 90)
			(layer "B.Fab")
			(effects
				(font
					(size 1.27 1.27)
				)
				(justify mirror)
			)
		)
		(duplicate_pad_numbers_are_jumpers no)
		(fp_line
			(start 1.524 -0.762)
			(end -1.524 -0.762)
			(stroke
				(width 0.1524)
				(type default)
			)
			(layer "B.SilkS")
		)
		(fp_line
			(start -1.524 -0.762)
			(end -1.524 0.762)
			(stroke
				(width 0.1524)
				(type default)
			)
			(layer "B.SilkS")
		)
		(fp_line
			(start 1.524 0.762)
			(end 1.524 -0.762)
			(stroke
				(width 0.1524)
				(type default)
			)
			(layer "B.SilkS")
		)
		(fp_line
			(start -1.524 0.762)
			(end 1.524 0.762)
			(stroke
				(width 0.1524)
				(type default)
			)
			(layer "B.SilkS")
		)
		(fp_line
			(start 1.1049 -0.724916)
			(end 1.1049 0.724916)
			(stroke
				(width 0.1)
				(type default)
			)
			(layer "B.Fab")
		)
		(fp_line
			(start -1.1049 -0.724916)
			(end 1.1049 -0.724916)
			(stroke
				(width 0.1)
				(type default)
			)
			(layer "B.Fab")
		)
		(fp_line
			(start 1.1049 0.724916)
			(end -1.1049 0.724916)
			(stroke
				(width 0.1)
				(type default)
			)
			(layer "B.Fab")
		)
		(fp_line
			(start -1.1049 0.724916)
			(end -1.1049 -0.724916)
			(stroke
				(width 0.1)
				(type default)
			)
			(layer "B.Fab")
		)
		(pad "1" smd rect
			(at 0.889 0 90)
			(size 1.016 1.27)
			(layers "B.Cu" "B.Mask" "B.Paste")
			(net "PVDDCR_CPU0_P1")
		)
		(pad "2" smd rect
			(at -0.889 0 90)
			(size 1.016 1.27)
			(layers "B.Cu" "B.Mask" "B.Paste")
			(net "GND")
		)
	)
	(footprint ""
		(layer "B.Cu")
		(at 59.404504 -408.517344 90)
		(property "Reference" "C6667"
			(at 0 0 90)
			(layer "B.SilkS")
			(hide yes)
			(effects
				(font
					(size 1.27 1.27)
				)
				(justify mirror)
			)
		)
		(property "Value" ""
			(at 0 0 90)
			(layer "B.Fab")
			(effects
				(font
					(size 1.27 1.27)
				)
				(justify mirror)
			)
		)
		(duplicate_pad_numbers_are_jumpers no)
		(fp_line
			(start 0.299974 -0.150114)
			(end -0.299974 -0.150114)
			(stroke
				(width 0.1)
				(type default)
			)
			(layer "B.Fab")
		)
		(fp_line
			(start -0.299974 -0.150114)
			(end -0.299974 0.150114)
			(stroke
				(width 0.1)
				(type default)
			)
			(layer "B.Fab")
		)
		(fp_line
			(start 0.299974 0.150114)
			(end 0.299974 -0.150114)
			(stroke
				(width 0.1)
				(type default)
			)
			(layer "B.Fab")
		)
		(fp_line
			(start -0.299974 0.150114)
			(end 0.299974 0.150114)
			(stroke
				(width 0.1)
				(type default)
			)
			(layer "B.Fab")
		)
		(pad "1" smd rect
			(at 0.2667 0 270)
			(size 0.3048 0.381)
			(layers "B.Cu" "B.Mask" "B.Paste")
			(net "P5E_CPU1_P1_TX_BUF_C_DP<3>")
		)
		(pad "2" smd rect
			(at -0.2667 0 270)
			(size 0.3048 0.381)
			(layers "B.Cu" "B.Mask" "B.Paste")
			(net "P5E_CPU1_P1_TX_BUF_DP<3>")
		)
	)
	(footprint ""
		(layer "B.Cu")
		(at 231.775 -216.662)
		(property "Reference" "R322"
			(at 0 0 0)
			(layer "B.SilkS")
			(hide yes)
			(effects
				(font
					(size 1.27 1.27)
				)
				(justify mirror)
			)
		)
		(property "Value" ""
			(at 0 0 0)
			(layer "B.Fab")
			(effects
				(font
					(size 1.27 1.27)
				)
				(justify mirror)
			)
		)
		(duplicate_pad_numbers_are_jumpers no)
		(fp_line
			(start -0.7874 -0.4064)
			(end -0.7874 0.4064)
			(stroke
				(width 0.1524)
				(type default)
			)
			(layer "B.SilkS")
		)
		(fp_line
			(start -0.7874 0.4064)
			(end 0.7874 0.4064)
			(stroke
				(width 0.1524)
				(type default)
			)
			(layer "B.SilkS")
		)
		(fp_line
			(start 0.7874 -0.4064)
			(end -0.7874 -0.4064)
			(stroke
				(width 0.1524)
				(type default)
			)
			(layer "B.SilkS")
		)
		(fp_line
			(start 0.7874 0.4064)
			(end 0.7874 -0.4064)
			(stroke
				(width 0.1524)
				(type default)
			)
			(layer "B.SilkS")
		)
		(fp_line
			(start -0.67945 -0.3048)
			(end -0.67945 0.3048)
			(stroke
				(width 0.1)
				(type default)
			)
			(layer "B.Fab")
		)
		(fp_line
			(start -0.67945 0.3048)
			(end -0.120396 0.3048)
			(stroke
				(width 0.1)
				(type default)
			)
			(layer "B.Fab")
		)
		(fp_line
			(start -0.12065 -0.3048)
			(end -0.67945 -0.3048)
			(stroke
				(width 0.1)
				(type default)
			)
			(layer "B.Fab")
		)
		(fp_line
			(start -0.12065 -0.2794)
			(end -0.12065 -0.3048)
			(stroke
				(width 0.1)
				(type default)
			)
			(layer "B.Fab")
		)
		(fp_line
			(start -0.120396 0.2794)
			(end 0.12065 0.2794)
			(stroke
				(width 0.1)
				(type default)
			)
			(layer "B.Fab")
		)
		(fp_line
			(start -0.120396 0.3048)
			(end -0.120396 0.2794)
			(stroke
				(width 0.1)
				(type default)
			)
			(layer "B.Fab")
		)
		(fp_line
			(start 0.12065 -0.305054)
			(end 0.12065 -0.2794)
			(stroke
				(width 0.1)
				(type default)
			)
			(layer "B.Fab")
		)
		(fp_line
			(start 0.12065 -0.2794)
			(end -0.12065 -0.2794)
			(stroke
				(width 0.1)
				(type default)
			)
			(layer "B.Fab")
		)
		(fp_line
			(start 0.12065 0.2794)
			(end 0.12065 0.3048)
			(stroke
				(width 0.1)
				(type default)
			)
			(layer "B.Fab")
		)
		(fp_line
			(start 0.12065 0.3048)
			(end 0.67945 0.3048)
			(stroke
				(width 0.1)
				(type default)
			)
			(layer "B.Fab")
		)
		(fp_line
			(start 0.67945 -0.305054)
			(end 0.12065 -0.305054)
			(stroke
				(width 0.1)
				(type default)
			)
			(layer "B.Fab")
		)
		(fp_line
			(start 0.67945 0.3048)
			(end 0.67945 -0.305054)
			(stroke
				(width 0.1)
				(type default)
			)
			(layer "B.Fab")
		)
		(pad "1" smd circle
			(at 0.40005 0 180)
			(size 0 0)
			(layers "B.Cu" "B.Mask" "B.Paste")
			(net "PVDD11_S3_P0")
		)
		(pad "2" smd circle
			(at -0.40005 0 180)
			(size 0 0)
			(layers "B.Cu" "B.Mask" "B.Paste")
			(net "SMB_CPU0_CPU1_APML_BUF2_SCL_R2")
		)
	)
)
